(kicad_pcb
	(version 20241229)
	(generator "pcbnew")
	(generator_version "9.0")
	(general
		(thickness 1.61)
		(legacy_teardrops no)
	)
	(paper "A3")
	(title_block
		(title "SO-DIMM DDR5 Tester")
		(date "2025-11-26")
		(rev "1.3.0")
		(comment 9 "footprints 96-98 of 627")
	)
	(layers
		(0 "F.Cu" signal)
		(4 "In1.Cu" power)
		(6 "In2.Cu" mixed)
		(8 "In3.Cu" power)
		(10 "In4.Cu" mixed)
		(12 "In5.Cu" power)
		(14 "In6.Cu" mixed)
		(16 "In7.Cu" power)
		(18 "In8.Cu" power)
		(20 "In9.Cu" mixed)
		(22 "In10.Cu" power)
		(2 "B.Cu" signal)
		(9 "F.Adhes" user "F.Adhesive")
		(11 "B.Adhes" user "B.Adhesive")
		(13 "F.Paste" user)
		(15 "B.Paste" user)
		(5 "F.SilkS" user "F.Silkscreen")
		(7 "B.SilkS" user "B.Silkscreen")
		(1 "F.Mask" user)
		(3 "B.Mask" user)
		(17 "Dwgs.User" user "User.Drawings")
		(19 "Cmts.User" user "User.Comments")
		(21 "Eco1.User" user "User.Eco1")
		(23 "Eco2.User" user "User.Eco2")
		(25 "Edge.Cuts" user)
		(27 "Margin" user)
		(31 "F.CrtYd" user "F.Courtyard")
		(29 "B.CrtYd" user "B.Courtyard")
		(35 "F.Fab" user)
		(33 "B.Fab" user)
	)
	(footprint "antmicro-footprints:SW_DIP_SPSTx03_Slide_Copal_CVS-03xB_W5.9mm_P1mm"
		(layer "F.Cu")
		(at 162.250501 180.675)
		(descr "SMD 3x-dip-switch SPST Copal_CVS-03xB, Slide, row spacing 5.9 mm (232 mils), body size  (see http://www.nidec-copal-electronics.com/e/catalog/switch/cvs.pdf)")
		(tags "SMD DIP Switch SPST Slide")
		(property "Reference" "SW1"
			(at -4.150501 3.825 0)
			(layer "F.SilkS")
			(effects
				(font
					(size 0.7 0.7)
					(thickness 0.15)
				)
				(justify left bottom)
			)
		)
		(property "Value" "CVS-03B"
			(at 0.248 4.799 0)
			(layer "F.Fab")
			(effects
				(font
					(size 0.7 0.7)
					(thickness 0.15)
				)
				(justify left bottom)
			)
		)
		(property "Datasheet" "https://www.mouser.com/datasheet/2/972/cvs-1827291.pdf"
			(at 0 0 0)
			(layer "F.Fab")
			(hide yes)
			(effects
				(font
					(size 1.27 1.27)
					(thickness 0.15)
				)
			)
		)
		(property "Author" "Antmicro"
			(at 0 0 0)
			(layer "F.Fab")
			(hide yes)
			(effects
				(font
					(size 1 1)
					(thickness 0.15)
				)
			)
		)
		(property "License" "Apache-2.0"
			(at 0 0 0)
			(layer "F.Fab")
			(hide yes)
			(effects
				(font
					(size 1 1)
					(thickness 0.15)
				)
			)
		)
		(property "MPN" "CVS-03B"
			(at 0 0 0)
			(layer "F.Fab")
			(hide yes)
			(effects
				(font
					(size 1 1)
					(thickness 0.15)
				)
			)
		)
		(property "Manufacturer" "Nidec Components"
			(at 0 0 0)
			(layer "F.Fab")
			(hide yes)
			(effects
				(font
					(size 1 1)
					(thickness 0.15)
				)
			)
		)
		(property ki_fp_filters "SW?DIP?x2*")
		(sheetname "/FPGA Config/")
		(sheetfile "fpga-config.kicad_sch")
		(attr smd)
		(fp_line
			(start -1.51 -2.411)
			(end 1.61 -2.411)
			(stroke
				(width 0.15)
				(type solid)
			)
			(layer "F.SilkS")
		)
		(fp_line
			(start -1.51 2.41)
			(end 1.61 2.41)
			(stroke
				(width 0.15)
				(type solid)
			)
			(layer "F.SilkS")
		)
		(fp_circle
			(center -3.33 -1.641)
			(end -3.281 -1.641)
			(stroke
				(width 0.15)
				(type solid)
			)
			(fill yes)
			(layer "F.SilkS")
		)
		(fp_rect
			(start -3.56 -2.5)
			(end 3.66 2.49)
			(stroke
				(width 0.05)
				(type solid)
			)
			(fill no)
			(layer "F.CrtYd")
		)
		(fp_line
			(start -2.301 -1)
			(end -1.301 -2)
			(stroke
				(width 0.15)
				(type solid)
			)
			(layer "F.Fab")
		)
		(fp_line
			(start -2.301 1.999)
			(end -2.301 -1)
			(stroke
				(width 0.15)
				(type solid)
			)
			(layer "F.Fab")
		)
		(fp_line
			(start -1.301 -2)
			(end 2.398 -2)
			(stroke
				(width 0.15)
				(type solid)
			)
			(layer "F.Fab")
		)
		(fp_line
			(start -0.951 -1.25)
			(end -0.951 -0.75)
			(stroke
				(width 0.15)
				(type solid)
			)
			(layer "F.Fab")
		)
		(fp_line
			(start -0.951 -1.151)
			(end -0.285 -1.151)
			(stroke
				(width 0.15)
				(type solid)
			)
			(layer "F.Fab")
		)
		(fp_line
			(start -0.951 -1.051)
			(end -0.285 -1.051)
			(stroke
				(width 0.15)
				(type solid)
			)
			(layer "F.Fab")
		)
		(fp_line
			(start -0.951 -0.952)
			(end -0.285 -0.952)
			(stroke
				(width 0.15)
				(type solid)
			)
			(layer "F.Fab")
		)
		(fp_line
			(start -0.951 -0.85)
			(end -0.285 -0.85)
			(stroke
				(width 0.15)
				(type solid)
			)
			(layer "F.Fab")
		)
		(fp_line
			(start -0.951 -0.75)
			(end 1.05 -0.75)
			(stroke
				(width 0.15)
				(type solid)
			)
			(layer "F.Fab")
		)
		(fp_line
			(start -0.951 -0.25)
			(end -0.951 0.247)
			(stroke
				(width 0.15)
				(type solid)
			)
			(layer "F.Fab")
		)
		(fp_line
			(start -0.951 -0.15)
			(end -0.285 -0.15)
			(stroke
				(width 0.15)
				(type solid)
			)
			(layer "F.Fab")
		)
		(fp_line
			(start -0.951 -0.053)
			(end -0.285 -0.053)
			(stroke
				(width 0.15)
				(type solid)
			)
			(layer "F.Fab")
		)
		(fp_line
			(start -0.951 0.05)
			(end -0.285 0.05)
			(stroke
				(width 0.15)
				(type solid)
			)
			(layer "F.Fab")
		)
		(fp_line
			(start -0.951 0.147)
			(end -0.285 0.147)
			(stroke
				(width 0.15)
				(type solid)
			)
			(layer "F.Fab")
		)
		(fp_line
			(start -0.951 0.247)
			(end 1.05 0.247)
			(stroke
				(width 0.15)
				(type solid)
			)
			(layer "F.Fab")
		)
		(fp_line
			(start -0.951 0.747)
			(end -0.951 1.249)
			(stroke
				(width 0.15)
				(type solid)
			)
			(layer "F.Fab")
		)
		(fp_line
			(start -0.951 0.847)
			(end -0.285 0.847)
			(stroke
				(width 0.15)
				(type solid)
			)
			(layer "F.Fab")
		)
		(fp_line
			(start -0.951 0.949)
			(end -0.285 0.949)
			(stroke
				(width 0.15)
				(type solid)
			)
			(layer "F.Fab")
		)
		(fp_line
			(start -0.951 1.05)
			(end -0.285 1.05)
			(stroke
				(width 0.15)
				(type solid)
			)
			(layer "F.Fab")
		)
		(fp_line
			(start -0.951 1.148)
			(end -0.285 1.148)
			(stroke
				(width 0.15)
				(type solid)
			)
			(layer "F.Fab")
		)
		(fp_line
			(start -0.951 1.249)
			(end 1.05 1.249)
			(stroke
				(width 0.15)
				(type solid)
			)
			(layer "F.Fab")
		)
		(fp_line
			(start -0.285 -1.25)
			(end -0.285 -0.75)
			(stroke
				(width 0.15)
				(type solid)
			)
			(layer "F.Fab")
		)
		(fp_line
			(start -0.285 -0.25)
			(end -0.285 0.247)
			(stroke
				(width 0.15)
				(type solid)
			)
			(layer "F.Fab")
		)
		(fp_line
			(start -0.285 0.747)
			(end -0.285 1.249)
			(stroke
				(width 0.15)
				(type solid)
			)
			(layer "F.Fab")
		)
		(fp_line
			(start 1.05 -1.25)
			(end -0.951 -1.25)
			(stroke
				(width 0.15)
				(type solid)
			)
			(layer "F.Fab")
		)
		(fp_line
			(start 1.05 -0.75)
			(end 1.05 -1.25)
			(stroke
				(width 0.15)
				(type solid)
			)
			(layer "F.Fab")
		)
		(fp_line
			(start 1.05 -0.25)
			(end -0.951 -0.25)
			(stroke
				(width 0.15)
				(type solid)
			)
			(layer "F.Fab")
		)
		(fp_line
			(start 1.05 0.247)
			(end 1.05 -0.25)
			(stroke
				(width 0.15)
				(type solid)
			)
			(layer "F.Fab")
		)
		(fp_line
			(start 1.05 0.747)
			(end -0.951 0.747)
			(stroke
				(width 0.15)
				(type solid)
			)
			(layer "F.Fab")
		)
		(fp_line
			(start 1.05 1.249)
			(end 1.05 0.747)
			(stroke
				(width 0.15)
				(type solid)
			)
			(layer "F.Fab")
		)
		(fp_line
			(start 2.398 -2)
			(end 2.398 1.999)
			(stroke
				(width 0.15)
				(type solid)
			)
			(layer "F.Fab")
		)
		(fp_line
			(start 2.398 1.999)
			(end -2.301 1.999)
			(stroke
				(width 0.15)
				(type solid)
			)
			(layer "F.Fab")
		)
		(fp_text user "on"
			(at -1.44 0.72 90)
			(layer "F.Fab")
			(effects
				(font
					(size 0.7 0.7)
					(thickness 0.15)
				)
				(justify left bottom)
			)
		)
		(pad "1" smd rect
			(at -2.899 -1)
			(size 1.2 0.5)
			(layers "F.Cu" "F.Mask" "F.Paste")
			(net 633 "/FPGA Config/MODE0")
			(pinfunction "1")
			(pintype "passive")
		)
		(pad "2" smd rect
			(at -2.899 0)
			(size 1.2 0.5)
			(layers "F.Cu" "F.Mask" "F.Paste")
			(net 632 "/FPGA Config/MODE1")
			(pinfunction "2")
			(pintype "passive")
		)
		(pad "3" smd rect
			(at -2.899 0.997)
			(size 1.2 0.5)
			(layers "F.Cu" "F.Mask" "F.Paste")
			(net 631 "/FPGA Config/MODE2")
			(pinfunction "3")
			(pintype "passive")
		)
		(pad "4" smd rect
			(at 2.999 0.997)
			(size 1.2 0.5)
			(layers "F.Cu" "F.Mask" "F.Paste")
			(net 1 "GND")
			(pinfunction "4")
			(pintype "passive")
		)
		(pad "5" smd rect
			(at 2.999 0)
			(size 1.2 0.5)
			(layers "F.Cu" "F.Mask" "F.Paste")
			(net 1 "GND")
			(pinfunction "5")
			(pintype "passive")
		)
		(pad "6" smd rect
			(at 2.999 -1)
			(size 1.2 0.5)
			(layers "F.Cu" "F.Mask" "F.Paste")
			(net 1 "GND")
			(pinfunction "6")
			(pintype "passive")
		)
		(pad "7" smd rect
			(at -2.101 -2)
			(size 0.7 0.7)
			(layers "F.Cu" "F.Mask" "F.Paste")
			(net 1 "GND")
			(pinfunction "7")
			(pintype "power_in")
		)
		(pad "7" smd rect
			(at -2.101 1.999)
			(size 0.7 0.7)
			(layers "F.Cu" "F.Mask" "F.Paste")
			(net 1 "GND")
			(pinfunction "7")
			(pintype "power_in")
		)
		(pad "7" smd rect
			(at 2.201 -2)
			(size 0.7 0.7)
			(layers "F.Cu" "F.Mask" "F.Paste")
			(net 1 "GND")
			(pinfunction "7")
			(pintype "power_in")
		)
		(pad "7" smd rect
			(at 2.201 1.999)
			(size 0.7 0.7)
			(layers "F.Cu" "F.Mask" "F.Paste")
			(net 1 "GND")
			(pinfunction "7")
			(pintype "power_in")
		)
	)
	(footprint "antmicro-footprints:SOT-23-6"
		(layer "F.Cu")
		(at 122.1 202.7)
		(property "Reference" "U18"
			(at 0.45 2.7 0)
			(layer "F.SilkS")
			(effects
				(font
					(size 0.7 0.7)
					(thickness 0.15)
				)
				(justify left bottom)
			)
		)
		(property "Value" "LTC4412IS6"
			(at -1.75 2.75 0)
			(layer "F.Fab")
			(effects
				(font
					(size 0.7 0.7)
					(thickness 0.15)
				)
				(justify left bottom)
			)
		)
		(property "Datasheet" "https://www.mouser.com/datasheet/2/308/NCV8187_D-1813214.pdf"
			(at 0 0 0)
			(layer "F.Fab")
			(hide yes)
			(effects
				(font
					(size 1.27 1.27)
					(thickness 0.15)
				)
			)
		)
		(property "Author" "Antmicro"
			(at 0 0 0)
			(layer "F.Fab")
			(hide yes)
			(effects
				(font
					(size 1 1)
					(thickness 0.15)
				)
			)
		)
		(property "License" "Apache-2.0"
			(at 0 0 0)
			(layer "F.Fab")
			(hide yes)
			(effects
				(font
					(size 1 1)
					(thickness 0.15)
				)
			)
		)
		(property "MPN" "LTC4412IS6#TRMPBF"
			(at 0 0 0)
			(layer "F.Fab")
			(hide yes)
			(effects
				(font
					(size 1 1)
					(thickness 0.15)
				)
			)
		)
		(property "Manufacturer" "Analog Devices"
			(at 0 0 0)
			(layer "F.Fab")
			(hide yes)
			(effects
				(font
					(size 1 1)
					(thickness 0.15)
				)
			)
		)
		(sheetname "/Supply/")
		(sheetfile "supply.kicad_sch")
		(attr smd)
		(fp_line
			(start -1.45 -0.7)
			(end -1.45 -0.4)
			(stroke
				(width 0.12)
				(type solid)
			)
			(layer "F.SilkS")
		)
		(fp_line
			(start -1.45 0.7)
			(end -1.45 0.4)
			(stroke
				(width 0.12)
				(type solid)
			)
			(layer "F.SilkS")
		)
		(fp_line
			(start -1.3 -0.7)
			(end -1.45 -0.7)
			(stroke
				(width 0.12)
				(type solid)
			)
			(layer "F.SilkS")
		)
		(fp_line
			(start 1.3 -0.7)
			(end 1.45 -0.7)
			(stroke
				(width 0.12)
				(type solid)
			)
			(layer "F.SilkS")
		)
		(fp_line
			(start 1.3 0.7)
			(end 1.45 0.7)
			(stroke
				(width 0.12)
				(type solid)
			)
			(layer "F.SilkS")
		)
		(fp_line
			(start 1.45 -0.7)
			(end 1.45 -0.4)
			(stroke
				(width 0.12)
				(type solid)
			)
			(layer "F.SilkS")
		)
		(fp_line
			(start 1.45 0.7)
			(end 1.45 0.4)
			(stroke
				(width 0.12)
				(type solid)
			)
			(layer "F.SilkS")
		)
		(fp_rect
			(start -1.55 -1.85)
			(end 1.55 1.75)
			(stroke
				(width 0.05)
				(type solid)
			)
			(fill no)
			(layer "F.CrtYd")
		)
		(fp_line
			(start -1.5 -0.7)
			(end 1.5 -0.7)
			(stroke
				(width 0.1)
				(type solid)
			)
			(layer "F.Fab")
		)
		(fp_line
			(start -1.5 0.7)
			(end -1.5 -0.7)
			(stroke
				(width 0.1)
				(type solid)
			)
			(layer "F.Fab")
		)
		(fp_line
			(start 1.5 -0.7)
			(end 1.5 0.7)
			(stroke
				(width 0.1)
				(type solid)
			)
			(layer "F.Fab")
		)
		(fp_line
			(start 1.5 0.7)
			(end -1.5 0.7)
			(stroke
				(width 0.1)
				(type solid)
			)
			(layer "F.Fab")
		)
		(fp_text user "."
			(at -1.4 1.2 180)
			(layer "F.SilkS")
			(effects
				(font
					(size 1 1)
					(thickness 0.15)
				)
			)
		)
		(pad "1" smd roundrect
			(at -0.954 1.1)
			(size 0.55 1)
			(layers "F.Cu" "F.Mask" "F.Paste")
			(roundrect_rratio 0.15)
			(net 596 "/Supply/12V_PCIE_fused")
			(pinfunction "IN")
			(pintype "power_in")
		)
		(pad "2" smd roundrect
			(at -0.003 1.1)
			(size 0.55 1)
			(layers "F.Cu" "F.Mask" "F.Paste")
			(roundrect_rratio 0.15)
			(net 1 "GND")
			(pinfunction "GND")
			(pintype "power_in")
		)
		(pad "3" smd roundrect
			(at 0.947 1.1)
			(size 0.55 1)
			(layers "F.Cu" "F.Mask" "F.Paste")
			(roundrect_rratio 0.15)
			(net 1 "GND")
			(pinfunction "CTL")
			(pintype "input")
		)
		(pad "4" smd roundrect
			(at 0.947 -1.214)
			(size 0.55 1)
			(layers "F.Cu" "F.Mask" "F.Paste")
			(roundrect_rratio 0.15)
			(net 725 "unconnected-(U18-STAT-Pad4)")
			(pinfunction "STAT")
			(pintype "output+no_connect")
		)
		(pad "5" smd roundrect
			(at -0.003 -1.214)
			(size 0.55 1)
			(layers "F.Cu" "F.Mask" "F.Paste")
			(roundrect_rratio 0.15)
			(net 366 "Net-(Q13-G)")
			(pinfunction "GATE")
			(pintype "output")
		)
		(pad "6" smd roundrect
			(at -0.954 -1.214)
			(size 0.55 1)
			(layers "F.Cu" "F.Mask" "F.Paste")
			(roundrect_rratio 0.15)
			(net 38 "VDC")
			(pinfunction "SENSE")
			(pintype "input")
		)
	)
	(footprint "antmicro-footprints:X2SON8_1.4x1x0.32mm_P0.35mm"
		(layer "F.Cu")
		(at 104.81 175.535)
		(property "Reference" "U32"
			(at -0.62 3.165 90)
			(layer "F.SilkS")
			(effects
				(font
					(size 0.7 0.7)
					(thickness 0.15)
				)
				(justify left bottom)
			)
		)
		(property "Value" "TXS0102DQER"
			(at 0 1.929 0)
			(layer "F.Fab")
			(effects
				(font
					(size 0.7 0.7)
					(thickness 0.15)
				)
				(justify left bottom)
			)
		)
		(property "Datasheet" "https://www.ti.com/lit/ds/symlink/txs0102.pdf?ts=1637914596981&ref_url=https%253A%252F%252Fwww.ti.com%252Fstore%252Fti%252Fen%252Fp%252Fproduct%252F%253Fp%253DTXS0102DCTR%2526keyMatch%253DTXS0102DCTR%2526tisearch%253Dsearch-everything%2526usecase%253DOPN"
			(at 0 0 0)
			(layer "F.Fab")
			(hide yes)
			(effects
				(font
					(size 1.27 1.27)
					(thickness 0.15)
				)
			)
		)
		(property "Author" "Antmicro"
			(at 0 0 0)
			(layer "F.Fab")
			(hide yes)
			(effects
				(font
					(size 1 1)
					(thickness 0.15)
				)
			)
		)
		(property "License" "Apache-2.0"
			(at 0 0 0)
			(layer "F.Fab")
			(hide yes)
			(effects
				(font
					(size 1 1)
					(thickness 0.15)
				)
			)
		)
		(property "MPN" "TXS0102DQER"
			(at 0 0 0)
			(layer "F.Fab")
			(hide yes)
			(effects
				(font
					(size 1 1)
					(thickness 0.15)
				)
			)
		)
		(property "Manufacturer" "Texas Instruments"
			(at 0 0 0)
			(layer "F.Fab")
			(hide yes)
			(effects
				(font
					(size 1 1)
					(thickness 0.15)
				)
			)
		)
		(sheetname "/Debug FTDI/")
		(sheetfile "debug-ftdi.kicad_sch")
		(attr smd)
		(fp_line
			(start -0.6 -0.801)
			(end -0.6 -0.7)
			(stroke
				(width 0.15)
				(type solid)
			)
			(layer "F.SilkS")
		)
		(fp_line
			(start -0.6 0.7)
			(end -0.6 0.801)
			(stroke
				(width 0.15)
				(type solid)
			)
			(layer "F.SilkS")
		)
		(fp_line
			(start -0.6 0.801)
			(end -0.5 0.801)
			(stroke
				(width 0.15)
				(type solid)
			)
			(layer "F.SilkS")
		)
		(fp_line
			(start -0.402 -0.801)
			(end -0.6 -0.801)
			(stroke
				(width 0.15)
				(type solid)
			)
			(layer "F.SilkS")
		)
		(fp_line
			(start 0.598 -0.801)
			(end 0.498 -0.801)
			(stroke
				(width 0.15)
				(type solid)
			)
			(layer "F.SilkS")
		)
		(fp_line
			(start 0.598 -0.7)
			(end 0.598 -0.801)
			(stroke
				(width 0.15)
				(type solid)
			)
			(layer "F.SilkS")
		)
		(fp_line
			(start 0.598 0.7)
			(end 0.598 0.801)
			(stroke
				(width 0.15)
				(type solid)
			)
			(layer "F.SilkS")
		)
		(fp_line
			(start 0.598 0.801)
			(end 0.498 0.801)
			(stroke
				(width 0.15)
				(type solid)
			)
			(layer "F.SilkS")
		)
		(fp_circle
			(center -0.81 -0.77)
			(end -0.81 -0.72)
			(stroke
				(width 0.15)
				(type solid)
			)
			(fill yes)
			(layer "F.SilkS")
		)
		(fp_rect
			(start 0.75 -0.925)
			(end -0.75 0.925)
			(stroke
				(width 0.05)
				(type solid)
			)
			(fill no)
			(layer "F.CrtYd")
		)
		(fp_line
			(start -0.5 -0.729)
			(end -0.5 0.719)
			(stroke
				(width 0.15)
				(type solid)
			)
			(layer "F.Fab")
		)
		(fp_line
			(start -0.5 -0.724)
			(end 0.498 -0.724)
			(stroke
				(width 0.15)
				(type solid)
			)
			(layer "F.Fab")
		)
		(fp_line
			(start -0.5 0.724)
			(end 0.498 0.724)
			(stroke
				(width 0.15)
				(type solid)
			)
			(layer "F.Fab")
		)
		(fp_line
			(start 0.498 -0.719)
			(end 0.498 0.719)
			(stroke
				(width 0.15)
				(type solid)
			)
			(layer "F.Fab")
		)
		(pad "1" smd rect
			(at -0.43 -0.526 270)
			(size 0.17 0.5)
			(layers "F.Cu" "F.Mask" "F.Paste")
			(net 6 "/Debug FTDI/FTDI_3V3")
			(pinfunction "VCCA")
			(pintype "power_in")
		)
		(pad "2" smd rect
			(at -0.43 -0.175 270)
			(size 0.17 0.5)
			(layers "F.Cu" "F.Mask" "F.Paste")
			(net 640 "/Debug FTDI/FTDI_UART0_RX")
			(pinfunction "A1")
			(pintype "bidirectional")
		)
		(pad "3" smd rect
			(at -0.43 0.175 270)
			(size 0.17 0.5)
			(layers "F.Cu" "F.Mask" "F.Paste")
			(net 638 "/Debug FTDI/FTDI_UART0_TX")
			(pinfunction "A2")
			(pintype "bidirectional")
		)
		(pad "4" smd rect
			(at -0.43 0.526 270)
			(size 0.17 0.5)
			(layers "F.Cu" "F.Mask" "F.Paste")
			(net 1 "GND")
			(pinfunction "GND")
			(pintype "power_in")
		)
		(pad "5" smd rect
			(at 0.43 0.526 270)
			(size 0.17 0.5)
			(layers "F.Cu" "F.Mask" "F.Paste")
			(net 6 "/Debug FTDI/FTDI_3V3")
			(pinfunction "OE")
			(pintype "tri_state")
		)
		(pad "6" smd rect
			(at 0.43 0.175 270)
			(size 0.17 0.5)
			(layers "F.Cu" "F.Mask" "F.Paste")
			(net 747 "Net-(U32-B2)")
			(pinfunction "B2")
			(pintype "bidirectional")
		)
		(pad "7" smd rect
			(at 0.43 -0.175 270)
			(size 0.17 0.5)
			(layers "F.Cu" "F.Mask" "F.Paste")
			(net 746 "Net-(U32-B1)")
			(pinfunction "B1")
			(pintype "bidirectional")
		)
		(pad "8" smd rect
			(at 0.43 -0.526 270)
			(size 0.17 0.5)
			(layers "F.Cu" "F.Mask" "F.Paste")
			(net 200 "+3V3")
			(pinfunction "VCCB")
			(pintype "power_in")
		)
	)
)
